# T6G (Grand Teton) — schematic netlist excerpt (pin names and nets, part order shuffled) for the footprints in the layout excerpt that follows; sources: Cadence DE-HDL packaged netlist, KiCad conversion of 04192023_DAF0TMB3IC0_F0TG_MB_C_brd_V02_OCP.brd

C112  Q_CAP  0.1UF 25V 10% X7R  pkg 0402  page 92 : A = P3V3_AUX ; B = GND
C2640  Q_CAP  22UF 4V 20% X6S  pkg C0402  page 70 : A = PVDD11_S3_P0 ; B = GND
PC444_1  Q_CAP  22UF 16V 20% X6S  pkg C0805  page 222 : A = SW_P12V_AUX_PVDDIO_P1_FLT ; B = GND

(kicad_pcb
	(version 20260206)
	(generator "pcbnew")
	(generator_version "10.0")
	(general
		(thickness 1.6)
		(legacy_teardrops no)
	)
	(paper "A4")
	(title_block
		(title "04192023_DAF0TMB3IC0_F0TG_MB_C_brd_V02_OCP.brd")
		(comment 1 "Grand Teton / footprints 7913-7915 of 8354")
	)
	(layers
		(0 "F.Cu" signal "TOP")
		(4 "In1.Cu" signal "GND")
		(6 "In2.Cu" signal "IN1")
		(8 "In3.Cu" signal "GND1")
		(10 "In4.Cu" signal "IN2")
		(12 "In5.Cu" signal "GND2")
		(14 "In6.Cu" signal "IN3")
		(16 "In7.Cu" signal "GND3")
		(18 "In8.Cu" signal "VCC")
		(20 "In9.Cu" signal "VCC1")
		(22 "In10.Cu" signal "GND4")
		(24 "In11.Cu" signal "IN4")
		(26 "In12.Cu" signal "GND5")
		(28 "In13.Cu" signal "IN5")
		(30 "In14.Cu" signal "GND6")
		(32 "In15.Cu" signal "IN6")
		(34 "In16.Cu" signal "GND7")
		(2 "B.Cu" signal "BOTTOM")
		(9 "F.Adhes" user "F.Adhesive")
		(11 "B.Adhes" user "B.Adhesive")
		(13 "F.Paste" user "Package Geometry/Pastemask Top")
		(15 "B.Paste" user "Package Geometry/Pastemask Bottom")
		(5 "F.SilkS" user "Ref Des/Silkscreen Top")
		(7 "B.SilkS" user "Ref Des/Silkscreen Bottom")
		(1 "F.Mask" user "Board Geometry/Soldermask Top")
		(3 "B.Mask" user "Board Geometry/Soldermask Bottom")
		(17 "Dwgs.User" user "User.Drawings")
		(19 "Cmts.User" user "User.Comments")
		(21 "Eco1.User" user "User.Eco1")
		(23 "Eco2.User" user "User.Eco2")
		(25 "Edge.Cuts" user "Board Geometry/Outline")
		(27 "Margin" user)
		(31 "F.CrtYd" user "Package Geometry/Place Bound Top")
		(29 "B.CrtYd" user "Package Geometry/Place Bound Bottom")
		(35 "F.Fab" user "Ref Des/Assembly Top")
		(33 "B.Fab" user "Ref Des/Assembly Bottom")
	)
	(footprint ""
		(layer "B.Cu")
		(at 453.432418 -193.99631)
		(property "Reference" "C112"
			(at 0 0 0)
			(layer "B.SilkS")
			(hide yes)
			(effects
				(font
					(size 1.27 1.27)
				)
				(justify mirror)
			)
		)
		(property "Value" ""
			(at 0 0 0)
			(layer "B.Fab")
			(effects
				(font
					(size 1.27 1.27)
				)
				(justify mirror)
			)
		)
		(duplicate_pad_numbers_are_jumpers no)
		(fp_line
			(start -0.7874 -0.4064)
			(end -0.7874 0.4064)
			(stroke
				(width 0.1524)
				(type default)
			)
			(layer "B.SilkS")
		)
		(fp_line
			(start -0.7874 0.4064)
			(end 0.7874 0.4064)
			(stroke
				(width 0.1524)
				(type default)
			)
			(layer "B.SilkS")
		)
		(fp_line
			(start 0.7874 -0.4064)
			(end -0.7874 -0.4064)
			(stroke
				(width 0.1524)
				(type default)
			)
			(layer "B.SilkS")
		)
		(fp_line
			(start 0.7874 0.4064)
			(end 0.7874 -0.4064)
			(stroke
				(width 0.1524)
				(type default)
			)
			(layer "B.SilkS")
		)
		(fp_line
			(start -0.67945 -0.3048)
			(end -0.67945 0.3048)
			(stroke
				(width 0.1)
				(type default)
			)
			(layer "B.Fab")
		)
		(fp_line
			(start -0.67945 0.3048)
			(end -0.120396 0.3048)
			(stroke
				(width 0.1)
				(type default)
			)
			(layer "B.Fab")
		)
		(fp_line
			(start -0.12065 -0.3048)
			(end -0.67945 -0.3048)
			(stroke
				(width 0.1)
				(type default)
			)
			(layer "B.Fab")
		)
		(fp_line
			(start -0.12065 -0.2794)
			(end -0.12065 -0.3048)
			(stroke
				(width 0.1)
				(type default)
			)
			(layer "B.Fab")
		)
		(fp_line
			(start -0.120396 0.2794)
			(end 0.12065 0.2794)
			(stroke
				(width 0.1)
				(type default)
			)
			(layer "B.Fab")
		)
		(fp_line
			(start -0.120396 0.3048)
			(end -0.120396 0.2794)
			(stroke
				(width 0.1)
				(type default)
			)
			(layer "B.Fab")
		)
		(fp_line
			(start 0.12065 -0.305054)
			(end 0.12065 -0.2794)
			(stroke
				(width 0.1)
				(type default)
			)
			(layer "B.Fab")
		)
		(fp_line
			(start 0.12065 -0.2794)
			(end -0.12065 -0.2794)
			(stroke
				(width 0.1)
				(type default)
			)
			(layer "B.Fab")
		)
		(fp_line
			(start 0.12065 0.2794)
			(end 0.12065 0.3048)
			(stroke
				(width 0.1)
				(type default)
			)
			(layer "B.Fab")
		)
		(fp_line
			(start 0.12065 0.3048)
			(end 0.67945 0.3048)
			(stroke
				(width 0.1)
				(type default)
			)
			(layer "B.Fab")
		)
		(fp_line
			(start 0.67945 -0.305054)
			(end 0.12065 -0.305054)
			(stroke
				(width 0.1)
				(type default)
			)
			(layer "B.Fab")
		)
		(fp_line
			(start 0.67945 0.3048)
			(end 0.67945 -0.305054)
			(stroke
				(width 0.1)
				(type default)
			)
			(layer "B.Fab")
		)
		(pad "1" smd circle
			(at 0.40005 0 180)
			(size 0 0)
			(layers "B.Cu" "B.Mask" "B.Paste")
			(net "P3V3_AUX")
		)
		(pad "2" smd circle
			(at -0.40005 0 180)
			(size 0 0)
			(layers "B.Cu" "B.Mask" "B.Paste")
			(net "GND")
		)
	)
	(footprint ""
		(layer "B.Cu")
		(at 365.709454 -266.00531)
		(property "Reference" "C2640"
			(at 0 0 0)
			(layer "B.SilkS")
			(hide yes)
			(effects
				(font
					(size 1.27 1.27)
				)
				(justify mirror)
			)
		)
		(property "Value" ""
			(at 0 0 0)
			(layer "B.Fab")
			(effects
				(font
					(size 1.27 1.27)
				)
				(justify mirror)
			)
		)
		(duplicate_pad_numbers_are_jumpers no)
		(fp_line
			(start -0.7874 -0.4064)
			(end -0.7874 0.4064)
			(stroke
				(width 0.1524)
				(type default)
			)
			(layer "B.SilkS")
		)
		(fp_line
			(start -0.7874 0.4064)
			(end 0.7874 0.4064)
			(stroke
				(width 0.1524)
				(type default)
			)
			(layer "B.SilkS")
		)
		(fp_line
			(start 0.7874 -0.4064)
			(end -0.7874 -0.4064)
			(stroke
				(width 0.1524)
				(type default)
			)
			(layer "B.SilkS")
		)
		(fp_line
			(start 0.7874 0.4064)
			(end 0.7874 -0.4064)
			(stroke
				(width 0.1524)
				(type default)
			)
			(layer "B.SilkS")
		)
		(fp_line
			(start -0.67945 -0.3048)
			(end -0.67945 0.3048)
			(stroke
				(width 0.1)
				(type default)
			)
			(layer "B.Fab")
		)
		(fp_line
			(start -0.67945 0.3048)
			(end -0.120396 0.3048)
			(stroke
				(width 0.1)
				(type default)
			)
			(layer "B.Fab")
		)
		(fp_line
			(start -0.12065 -0.3048)
			(end -0.67945 -0.3048)
			(stroke
				(width 0.1)
				(type default)
			)
			(layer "B.Fab")
		)
		(fp_line
			(start -0.12065 -0.2794)
			(end -0.12065 -0.3048)
			(stroke
				(width 0.1)
				(type default)
			)
			(layer "B.Fab")
		)
		(fp_line
			(start -0.120396 0.2794)
			(end 0.12065 0.2794)
			(stroke
				(width 0.1)
				(type default)
			)
			(layer "B.Fab")
		)
		(fp_line
			(start -0.120396 0.3048)
			(end -0.120396 0.2794)
			(stroke
				(width 0.1)
				(type default)
			)
			(layer "B.Fab")
		)
		(fp_line
			(start 0.12065 -0.305054)
			(end 0.12065 -0.2794)
			(stroke
				(width 0.1)
				(type default)
			)
			(layer "B.Fab")
		)
		(fp_line
			(start 0.12065 -0.2794)
			(end -0.12065 -0.2794)
			(stroke
				(width 0.1)
				(type default)
			)
			(layer "B.Fab")
		)
		(fp_line
			(start 0.12065 0.2794)
			(end 0.12065 0.3048)
			(stroke
				(width 0.1)
				(type default)
			)
			(layer "B.Fab")
		)
		(fp_line
			(start 0.12065 0.3048)
			(end 0.67945 0.3048)
			(stroke
				(width 0.1)
				(type default)
			)
			(layer "B.Fab")
		)
		(fp_line
			(start 0.67945 -0.305054)
			(end 0.12065 -0.305054)
			(stroke
				(width 0.1)
				(type default)
			)
			(layer "B.Fab")
		)
		(fp_line
			(start 0.67945 0.3048)
			(end 0.67945 -0.305054)
			(stroke
				(width 0.1)
				(type default)
			)
			(layer "B.Fab")
		)
		(pad "1" smd circle
			(at 0.40005 0 180)
			(size 0 0)
			(layers "B.Cu" "B.Mask" "B.Paste")
			(net "PVDD11_S3_P0")
		)
		(pad "2" smd circle
			(at -0.40005 0 180)
			(size 0 0)
			(layers "B.Cu" "B.Mask" "B.Paste")
			(net "GND")
		)
	)
	(footprint ""
		(layer "B.Cu")
		(at 56.79313 -346.788994 90)
		(property "Reference" "PC444_1"
			(at 0 0 90)
			(layer "B.SilkS")
			(hide yes)
			(effects
				(font
					(size 1.27 1.27)
				)
				(justify mirror)
			)
		)
		(property "Value" ""
			(at 0 0 90)
			(layer "B.Fab")
			(effects
				(font
					(size 1.27 1.27)
				)
				(justify mirror)
			)
		)
		(duplicate_pad_numbers_are_jumpers no)
		(fp_line
			(start 1.524 -0.762)
			(end -1.524 -0.762)
			(stroke
				(width 0.1524)
				(type default)
			)
			(layer "B.SilkS")
		)
		(fp_line
			(start -1.524 -0.762)
			(end -1.524 0.762)
			(stroke
				(width 0.1524)
				(type default)
			)
			(layer "B.SilkS")
		)
		(fp_line
			(start 1.524 0.762)
			(end 1.524 -0.762)
			(stroke
				(width 0.1524)
				(type default)
			)
			(layer "B.SilkS")
		)
		(fp_line
			(start -1.524 0.762)
			(end 1.524 0.762)
			(stroke
				(width 0.1524)
				(type default)
			)
			(layer "B.SilkS")
		)
		(fp_line
			(start 1.1049 -0.724916)
			(end 1.1049 0.724916)
			(stroke
				(width 0.1)
				(type default)
			)
			(layer "B.Fab")
		)
		(fp_line
			(start -1.1049 -0.724916)
			(end 1.1049 -0.724916)
			(stroke
				(width 0.1)
				(type default)
			)
			(layer "B.Fab")
		)
		(fp_line
			(start 1.1049 0.724916)
			(end -1.1049 0.724916)
			(stroke
				(width 0.1)
				(type default)
			)
			(layer "B.Fab")
		)
		(fp_line
			(start -1.1049 0.724916)
			(end -1.1049 -0.724916)
			(stroke
				(width 0.1)
				(type default)
			)
			(layer "B.Fab")
		)
		(pad "1" smd rect
			(at 0.889 0 90)
			(size 1.016 1.27)
			(layers "B.Cu" "B.Mask" "B.Paste")
			(net "SW_P12V_AUX_PVDDIO_P1_FLT")
		)
		(pad "2" smd rect
			(at -0.889 0 90)
			(size 1.016 1.27)
			(layers "B.Cu" "B.Mask" "B.Paste")
			(net "GND")
		)
	)
)
